# T6G (Grand Teton) — schematic netlist excerpt (pin names and nets, part order shuffled) for the footprints in the layout excerpt that follows; sources: Cadence DE-HDL packaged netlist, KiCad conversion of 04192023_DAF0TMB3IC0_F0TG_MB_C_brd_V02_OCP.brd

R852  Q_RES  0 5% EMPTY  pkg 0402LF  page 345 : A = P1V8_CPU1_RT2_1A_1D ; B = P1V8_CPU1_RT2_1A
R6203  Q_RES  6.04K 1% CHIP  pkg 0402LF  page 176 : A = GND ; B = USB_CPU0_HUB1_RREF_USB2

(kicad_pcb
	(version 20260206)
	(generator "pcbnew")
	(generator_version "10.0")
	(general
		(thickness 1.6)
		(legacy_teardrops no)
	)
	(paper "A4")
	(title_block
		(title "04192023_DAF0TMB3IC0_F0TG_MB_C_brd_V02_OCP.brd")
		(comment 1 "Grand Teton / footprints 1272-1273 of 8354")
	)
	(layers
		(0 "F.Cu" signal "TOP")
		(4 "In1.Cu" signal "GND")
		(6 "In2.Cu" signal "IN1")
		(8 "In3.Cu" signal "GND1")
		(10 "In4.Cu" signal "IN2")
		(12 "In5.Cu" signal "GND2")
		(14 "In6.Cu" signal "IN3")
		(16 "In7.Cu" signal "GND3")
		(18 "In8.Cu" signal "VCC")
		(20 "In9.Cu" signal "VCC1")
		(22 "In10.Cu" signal "GND4")
		(24 "In11.Cu" signal "IN4")
		(26 "In12.Cu" signal "GND5")
		(28 "In13.Cu" signal "IN5")
		(30 "In14.Cu" signal "GND6")
		(32 "In15.Cu" signal "IN6")
		(34 "In16.Cu" signal "GND7")
		(2 "B.Cu" signal "BOTTOM")
		(9 "F.Adhes" user "F.Adhesive")
		(11 "B.Adhes" user "B.Adhesive")
		(13 "F.Paste" user "Package Geometry/Pastemask Top")
		(15 "B.Paste" user "Package Geometry/Pastemask Bottom")
		(5 "F.SilkS" user "Ref Des/Silkscreen Top")
		(7 "B.SilkS" user "Ref Des/Silkscreen Bottom")
		(1 "F.Mask" user "Board Geometry/Soldermask Top")
		(3 "B.Mask" user "Board Geometry/Soldermask Bottom")
		(17 "Dwgs.User" user "User.Drawings")
		(19 "Cmts.User" user "User.Comments")
		(21 "Eco1.User" user "User.Eco1")
		(23 "Eco2.User" user "User.Eco2")
		(25 "Edge.Cuts" user "Board Geometry/Outline")
		(27 "Margin" user)
		(31 "F.CrtYd" user "Package Geometry/Place Bound Top")
		(29 "B.CrtYd" user "Package Geometry/Place Bound Bottom")
		(35 "F.Fab" user "Ref Des/Assembly Top")
		(33 "B.Fab" user "Ref Des/Assembly Bottom")
	)
	(footprint ""
		(layer "F.Cu")
		(at 170.46956 -387.763004 180)
		(property "Reference" "R852"
			(at 0 0 180)
			(layer "F.SilkS")
			(hide yes)
			(effects
				(font
					(size 1.27 1.27)
				)
			)
		)
		(property "Value" ""
			(at 0 0 180)
			(layer "F.Fab")
			(effects
				(font
					(size 1.27 1.27)
				)
			)
		)
		(duplicate_pad_numbers_are_jumpers no)
		(fp_line
			(start 0.7874 0.4064)
			(end -0.7874 0.4064)
			(stroke
				(width 0.1524)
				(type default)
			)
			(layer "F.SilkS")
		)
		(fp_line
			(start 0.7874 -0.4064)
			(end 0.7874 0.4064)
			(stroke
				(width 0.1524)
				(type default)
			)
			(layer "F.SilkS")
		)
		(fp_line
			(start -0.7874 0.4064)
			(end -0.7874 -0.4064)
			(stroke
				(width 0.1524)
				(type default)
			)
			(layer "F.SilkS")
		)
		(fp_line
			(start -0.7874 -0.4064)
			(end 0.7874 -0.4064)
			(stroke
				(width 0.1524)
				(type default)
			)
			(layer "F.SilkS")
		)
		(fp_line
			(start 0.67945 0.3048)
			(end 0.120396 0.3048)
			(stroke
				(width 0.1)
				(type default)
			)
			(layer "F.Fab")
		)
		(fp_line
			(start 0.67945 -0.3048)
			(end 0.67945 0.3048)
			(stroke
				(width 0.1)
				(type default)
			)
			(layer "F.Fab")
		)
		(fp_line
			(start 0.12065 -0.2794)
			(end 0.12065 -0.3048)
			(stroke
				(width 0.1)
				(type default)
			)
			(layer "F.Fab")
		)
		(fp_line
			(start 0.12065 -0.3048)
			(end 0.67945 -0.3048)
			(stroke
				(width 0.1)
				(type default)
			)
			(layer "F.Fab")
		)
		(fp_line
			(start 0.120396 0.3048)
			(end 0.120396 0.2794)
			(stroke
				(width 0.1)
				(type default)
			)
			(layer "F.Fab")
		)
		(fp_line
			(start 0.120396 0.2794)
			(end -0.12065 0.2794)
			(stroke
				(width 0.1)
				(type default)
			)
			(layer "F.Fab")
		)
		(fp_line
			(start -0.12065 0.3048)
			(end -0.67945 0.3048)
			(stroke
				(width 0.1)
				(type default)
			)
			(layer "F.Fab")
		)
		(fp_line
			(start -0.12065 0.2794)
			(end -0.12065 0.3048)
			(stroke
				(width 0.1)
				(type default)
			)
			(layer "F.Fab")
		)
		(fp_line
			(start -0.12065 -0.2794)
			(end 0.12065 -0.2794)
			(stroke
				(width 0.1)
				(type default)
			)
			(layer "F.Fab")
		)
		(fp_line
			(start -0.12065 -0.305054)
			(end -0.12065 -0.2794)
			(stroke
				(width 0.1)
				(type default)
			)
			(layer "F.Fab")
		)
		(fp_line
			(start -0.67945 0.3048)
			(end -0.67945 -0.305054)
			(stroke
				(width 0.1)
				(type default)
			)
			(layer "F.Fab")
		)
		(fp_line
			(start -0.67945 -0.305054)
			(end -0.12065 -0.305054)
			(stroke
				(width 0.1)
				(type default)
			)
			(layer "F.Fab")
		)
		(pad "1" smd rect
			(at -0.40005 0)
			(size 0.4572 0.508)
			(layers "F.Cu" "F.Mask" "F.Paste")
			(net "P1V8_CPU1_RT2_1A_1D")
		)
		(pad "2" smd rect
			(at 0.40005 0)
			(size 0.4572 0.508)
			(layers "F.Cu" "F.Mask" "F.Paste")
			(net "P1V8_CPU1_RT2_1A")
		)
	)
	(footprint ""
		(layer "F.Cu")
		(at 137.955274 -31.70682 90)
		(property "Reference" "R6203"
			(at 0 0 90)
			(layer "F.SilkS")
			(hide yes)
			(effects
				(font
					(size 1.27 1.27)
				)
			)
		)
		(property "Value" ""
			(at 0 0 90)
			(layer "F.Fab")
			(effects
				(font
					(size 1.27 1.27)
				)
			)
		)
		(duplicate_pad_numbers_are_jumpers no)
		(fp_line
			(start 0.7874 -0.4064)
			(end 0.7874 0.4064)
			(stroke
				(width 0.1524)
				(type default)
			)
			(layer "F.SilkS")
		)
		(fp_line
			(start -0.7874 -0.4064)
			(end 0.7874 -0.4064)
			(stroke
				(width 0.1524)
				(type default)
			)
			(layer "F.SilkS")
		)
		(fp_line
			(start 0.7874 0.4064)
			(end -0.7874 0.4064)
			(stroke
				(width 0.1524)
				(type default)
			)
			(layer "F.SilkS")
		)
		(fp_line
			(start -0.7874 0.4064)
			(end -0.7874 -0.4064)
			(stroke
				(width 0.1524)
				(type default)
			)
			(layer "F.SilkS")
		)
		(fp_line
			(start -0.12065 -0.305054)
			(end -0.12065 -0.2794)
			(stroke
				(width 0.1)
				(type default)
			)
			(layer "F.Fab")
		)
		(fp_line
			(start -0.67945 -0.305054)
			(end -0.12065 -0.305054)
			(stroke
				(width 0.1)
				(type default)
			)
			(layer "F.Fab")
		)
		(fp_line
			(start 0.67945 -0.3048)
			(end 0.67945 0.3048)
			(stroke
				(width 0.1)
				(type default)
			)
			(layer "F.Fab")
		)
		(fp_line
			(start 0.12065 -0.3048)
			(end 0.67945 -0.3048)
			(stroke
				(width 0.1)
				(type default)
			)
			(layer "F.Fab")
		)
		(fp_line
			(start 0.12065 -0.2794)
			(end 0.12065 -0.3048)
			(stroke
				(width 0.1)
				(type default)
			)
			(layer "F.Fab")
		)
		(fp_line
			(start -0.12065 -0.2794)
			(end 0.12065 -0.2794)
			(stroke
				(width 0.1)
				(type default)
			)
			(layer "F.Fab")
		)
		(fp_line
			(start 0.120396 0.2794)
			(end -0.12065 0.2794)
			(stroke
				(width 0.1)
				(type default)
			)
			(layer "F.Fab")
		)
		(fp_line
			(start -0.12065 0.2794)
			(end -0.12065 0.3048)
			(stroke
				(width 0.1)
				(type default)
			)
			(layer "F.Fab")
		)
		(fp_line
			(start 0.67945 0.3048)
			(end 0.120396 0.3048)
			(stroke
				(width 0.1)
				(type default)
			)
			(layer "F.Fab")
		)
		(fp_line
			(start 0.120396 0.3048)
			(end 0.120396 0.2794)
			(stroke
				(width 0.1)
				(type default)
			)
			(layer "F.Fab")
		)
		(fp_line
			(start -0.12065 0.3048)
			(end -0.67945 0.3048)
			(stroke
				(width 0.1)
				(type default)
			)
			(layer "F.Fab")
		)
		(fp_line
			(start -0.67945 0.3048)
			(end -0.67945 -0.305054)
			(stroke
				(width 0.1)
				(type default)
			)
			(layer "F.Fab")
		)
		(pad "1" smd circle
			(at -0.40005 0 90)
			(size 0 0)
			(layers "F.Cu" "F.Mask" "F.Paste")
			(net "GND")
		)
		(pad "2" smd circle
			(at 0.40005 0 90)
			(size 0 0)
			(layers "F.Cu" "F.Mask" "F.Paste")
			(net "USB_CPU0_HUB1_RREF_USB2")
		)
	)
)
